(kicad_pcb
	(version 20241229)
	(generator "pcbnew")
	(generator_version "9.0")
	(general
		(thickness 1.62)
		(legacy_teardrops no)
	)
	(paper "A3")
	(title_block
		(title "COM Express 7 Baseboard")
		(date "2025-02-04")
		(rev "1.1.2")
		(company "Antmicro Ltd")
		(comment 1 "www.antmicro.com")
		(comment 9 "footprints 185-185 of 802")
	)
	(layers
		(0 "F.Cu" signal)
		(4 "In1.Cu" signal)
		(6 "In2.Cu" signal)
		(8 "In3.Cu" signal)
		(10 "In4.Cu" signal)
		(12 "In5.Cu" signal)
		(14 "In6.Cu" signal)
		(2 "B.Cu" signal)
		(9 "F.Adhes" user "F.Adhesive")
		(11 "B.Adhes" user "B.Adhesive")
		(13 "F.Paste" user)
		(15 "B.Paste" user)
		(5 "F.SilkS" user "F.Silkscreen")
		(7 "B.SilkS" user "B.Silkscreen")
		(1 "F.Mask" user)
		(3 "B.Mask" user)
		(17 "Dwgs.User" user "User.Drawings")
		(19 "Cmts.User" user "User.Comments")
		(21 "Eco1.User" user "User.Eco1")
		(23 "Eco2.User" user "User.Eco2")
		(25 "Edge.Cuts" user)
		(27 "Margin" user)
		(31 "F.CrtYd" user "F.Courtyard")
		(29 "B.CrtYd" user "B.Courtyard")
		(35 "F.Fab" user)
		(33 "B.Fab" user)
	)
	(footprint "antmicro-footprints:QFN-24-1EP_4x4mm_P0.5_EP2.1x2.1mm"
		(layer "F.Cu")
		(at 130.65 85.56)
		(property "Reference" "U41"
			(at 0.2 3.45 0)
			(layer "F.SilkS")
			(effects
				(font
					(size 0.7 0.7)
					(thickness 0.15)
				)
				(justify left bottom)
			)
		)
		(property "Value" "PCA9539AHF"
			(at 0 3.4 0)
			(layer "F.Fab")
			(effects
				(font
					(size 0.7 0.7)
					(thickness 0.15)
				)
				(justify left bottom)
			)
		)
		(property "Datasheet" "https://www.nxp.com/docs/en/data-sheet/PCA9539A.pdf"
			(at 0 0 0)
			(layer "F.Fab")
			(hide yes)
			(effects
				(font
					(size 1.27 1.27)
					(thickness 0.15)
				)
			)
		)
		(property "Author" "Antmicro"
			(at 0 0 0)
			(layer "F.Fab")
			(hide yes)
			(effects
				(font
					(size 1 1)
					(thickness 0.15)
				)
			)
		)
		(property "License" "Apache-2.0"
			(at 0 0 0)
			(layer "F.Fab")
			(hide yes)
			(effects
				(font
					(size 1 1)
					(thickness 0.15)
				)
			)
		)
		(property "MPN" "PCA9539AHF,128"
			(at 0 0 0)
			(layer "F.Fab")
			(hide yes)
			(effects
				(font
					(size 1 1)
					(thickness 0.15)
				)
			)
		)
		(property "Manufacturer" "NXP"
			(at 0 0 0)
			(layer "F.Fab")
			(hide yes)
			(effects
				(font
					(size 1 1)
					(thickness 0.15)
				)
			)
		)
		(property ki_fp_filters "VFQFN-16-1EP_3x3mm")
		(sheetname "GPIO expander")
		(sheetfile "gpio_exp.kicad_sch")
		(attr smd)
		(fp_line
			(start -2.11 -1.636)
			(end -2.11 -2.11)
			(stroke
				(width 0.15)
				(type solid)
			)
			(layer "F.SilkS")
		)
		(fp_line
			(start -2.11 2.108)
			(end -2.11 1.634)
			(stroke
				(width 0.15)
				(type solid)
			)
			(layer "F.SilkS")
		)
		(fp_line
			(start -1.635 -2.11)
			(end -2.11 -2.11)
			(stroke
				(width 0.15)
				(type solid)
			)
			(layer "F.SilkS")
		)
		(fp_line
			(start -1.635 2.108)
			(end -2.11 2.108)
			(stroke
				(width 0.15)
				(type solid)
			)
			(layer "F.SilkS")
		)
		(fp_line
			(start 1.634 -2.11)
			(end 2.108 -2.11)
			(stroke
				(width 0.15)
				(type solid)
			)
			(layer "F.SilkS")
		)
		(fp_line
			(start 1.634 2.108)
			(end 2.108 2.108)
			(stroke
				(width 0.15)
				(type solid)
			)
			(layer "F.SilkS")
		)
		(fp_line
			(start 2.108 -2.11)
			(end 2.108 -1.635)
			(stroke
				(width 0.15)
				(type solid)
			)
			(layer "F.SilkS")
		)
		(fp_line
			(start 2.108 2.108)
			(end 2.108 1.634)
			(stroke
				(width 0.15)
				(type solid)
			)
			(layer "F.SilkS")
		)
		(fp_circle
			(center -2.3 -2.3)
			(end -2.25 -2.3)
			(stroke
				(width 0.15)
				(type solid)
			)
			(fill yes)
			(layer "F.SilkS")
		)
		(fp_rect
			(start -2.503 -2.503)
			(end 2.5 2.5)
			(stroke
				(width 0.05)
				(type solid)
			)
			(fill no)
			(layer "F.CrtYd")
		)
		(fp_line
			(start -2 -1)
			(end -1 -2)
			(stroke
				(width 0.15)
				(type solid)
			)
			(layer "F.Fab")
		)
		(fp_line
			(start -2 1.999)
			(end -2 -1)
			(stroke
				(width 0.15)
				(type solid)
			)
			(layer "F.Fab")
		)
		(fp_line
			(start -1 -2)
			(end 1.999 -2)
			(stroke
				(width 0.15)
				(type solid)
			)
			(layer "F.Fab")
		)
		(fp_line
			(start 1.999 -2)
			(end 1.999 1.999)
			(stroke
				(width 0.15)
				(type solid)
			)
			(layer "F.Fab")
		)
		(fp_line
			(start 1.999 1.999)
			(end -2 1.999)
			(stroke
				(width 0.15)
				(type solid)
			)
			(layer "F.Fab")
		)
		(pad "" smd roundrect
			(at -0.5 -0.5)
			(size 0.8 0.8)
			(layers "F.Paste")
			(roundrect_rratio 0.238095)
			(teardrops
				(best_length_ratio 0.2)
				(max_length 1)
				(best_width_ratio 0.9)
				(max_width 2)
				(curved_edges yes)
				(filter_ratio 0.9)
				(enabled yes)
				(allow_two_segments yes)
				(prefer_zone_connections yes)
			)
		)
		(pad "" smd roundrect
			(at -0.5 0.5)
			(size 0.8 0.8)
			(layers "F.Paste")
			(roundrect_rratio 0.238095)
			(teardrops
				(best_length_ratio 0.2)
				(max_length 1)
				(best_width_ratio 0.9)
				(max_width 2)
				(curved_edges yes)
				(filter_ratio 0.9)
				(enabled yes)
				(allow_two_segments yes)
				(prefer_zone_connections yes)
			)
		)
		(pad "" smd roundrect
			(at 0.5 -0.5)
			(size 0.8 0.8)
			(layers "F.Paste")
			(roundrect_rratio 0.238095)
			(teardrops
				(best_length_ratio 0.2)
				(max_length 1)
				(best_width_ratio 0.9)
				(max_width 2)
				(curved_edges yes)
				(filter_ratio 0.9)
				(enabled yes)
				(allow_two_segments yes)
				(prefer_zone_connections yes)
			)
		)
		(pad "" smd roundrect
			(at 0.5 0.5)
			(size 0.8 0.8)
			(layers "F.Paste")
			(roundrect_rratio 0.238095)
			(teardrops
				(best_length_ratio 0.2)
				(max_length 1)
				(best_width_ratio 0.9)
				(max_width 2)
				(curved_edges yes)
				(filter_ratio 0.9)
				(enabled yes)
				(allow_two_segments yes)
				(prefer_zone_connections yes)
			)
		)
		(pad "1" smd roundrect
			(at -1.938 -1.25)
			(size 0.825 0.25)
			(layers "F.Cu" "F.Mask" "F.Paste")
			(roundrect_rratio 0.25)
			(net 639 "Net-(U41-IO0_0)")
			(pinfunction "IO0_0")
			(pintype "bidirectional")
			(teardrops
				(best_length_ratio 0.2)
				(max_length 1)
				(best_width_ratio 0.9)
				(max_width 2)
				(curved_edges yes)
				(filter_ratio 0.9)
				(enabled yes)
				(allow_two_segments yes)
				(prefer_zone_connections yes)
			)
		)
		(pad "2" smd roundrect
			(at -1.938 -0.75)
			(size 0.825 0.25)
			(layers "F.Cu" "F.Mask" "F.Paste")
			(roundrect_rratio 0.25)
			(net 640 "Net-(U41-IO0_1)")
			(pinfunction "IO0_1")
			(pintype "bidirectional")
			(teardrops
				(best_length_ratio 0.2)
				(max_length 1)
				(best_width_ratio 0.9)
				(max_width 2)
				(curved_edges yes)
				(filter_ratio 0.9)
				(enabled yes)
				(allow_two_segments yes)
				(prefer_zone_connections yes)
			)
		)
		(pad "3" smd roundrect
			(at -1.938 -0.25)
			(size 0.825 0.25)
			(layers "F.Cu" "F.Mask" "F.Paste")
			(roundrect_rratio 0.25)
			(net 641 "Net-(U41-IO0_2)")
			(pinfunction "IO0_2")
			(pintype "bidirectional")
			(teardrops
				(best_length_ratio 0.2)
				(max_length 1)
				(best_width_ratio 0.9)
				(max_width 2)
				(curved_edges yes)
				(filter_ratio 0.9)
				(enabled yes)
				(allow_two_segments yes)
				(prefer_zone_connections yes)
			)
		)
		(pad "4" smd roundrect
			(at -1.938 0.248)
			(size 0.825 0.25)
			(layers "F.Cu" "F.Mask" "F.Paste")
			(roundrect_rratio 0.25)
			(net 642 "Net-(U41-IO0_3)")
			(pinfunction "IO0_3")
			(pintype "bidirectional")
			(teardrops
				(best_length_ratio 0.2)
				(max_length 1)
				(best_width_ratio 0.9)
				(max_width 2)
				(curved_edges yes)
				(filter_ratio 0.9)
				(enabled yes)
				(allow_two_segments yes)
				(prefer_zone_connections yes)
			)
		)
		(pad "5" smd roundrect
			(at -1.938 0.748)
			(size 0.825 0.25)
			(layers "F.Cu" "F.Mask" "F.Paste")
			(roundrect_rratio 0.25)
			(net 643 "Net-(U41-IO0_4)")
			(pinfunction "IO0_4")
			(pintype "bidirectional")
			(teardrops
				(best_length_ratio 0.2)
				(max_length 1)
				(best_width_ratio 0.9)
				(max_width 2)
				(curved_edges yes)
				(filter_ratio 0.9)
				(enabled yes)
				(allow_two_segments yes)
				(prefer_zone_connections yes)
			)
		)
		(pad "6" smd roundrect
			(at -1.938 1.249)
			(size 0.825 0.25)
			(layers "F.Cu" "F.Mask" "F.Paste")
			(roundrect_rratio 0.25)
			(net 644 "Net-(U41-IO0_5)")
			(pinfunction "IO0_5")
			(pintype "bidirectional")
			(teardrops
				(best_length_ratio 0.2)
				(max_length 1)
				(best_width_ratio 0.9)
				(max_width 2)
				(curved_edges yes)
				(filter_ratio 0.9)
				(enabled yes)
				(allow_two_segments yes)
				(prefer_zone_connections yes)
			)
		)
		(pad "7" smd roundrect
			(at -1.25 1.937)
			(size 0.25 0.825)
			(layers "F.Cu" "F.Mask" "F.Paste")
			(roundrect_rratio 0.25)
			(net 645 "Net-(U41-IO0_6)")
			(pinfunction "IO0_6")
			(pintype "bidirectional")
			(teardrops
				(best_length_ratio 0.2)
				(max_length 1)
				(best_width_ratio 0.9)
				(max_width 2)
				(curved_edges yes)
				(filter_ratio 0.9)
				(enabled yes)
				(allow_two_segments yes)
				(prefer_zone_connections yes)
			)
		)
		(pad "8" smd roundrect
			(at -0.75 1.937)
			(size 0.25 0.825)
			(layers "F.Cu" "F.Mask" "F.Paste")
			(roundrect_rratio 0.25)
			(net 646 "Net-(U41-IO0_7)")
			(pinfunction "IO0_7")
			(pintype "bidirectional")
			(teardrops
				(best_length_ratio 0.2)
				(max_length 1)
				(best_width_ratio 0.9)
				(max_width 2)
				(curved_edges yes)
				(filter_ratio 0.9)
				(enabled yes)
				(allow_two_segments yes)
				(prefer_zone_connections yes)
			)
		)
		(pad "9" smd roundrect
			(at -0.25 1.937)
			(size 0.25 0.825)
			(layers "F.Cu" "F.Mask" "F.Paste")
			(roundrect_rratio 0.25)
			(net 1 "GND")
			(pinfunction "GND")
			(pintype "power_in")
			(teardrops
				(best_length_ratio 0.2)
				(max_length 1)
				(best_width_ratio 0.9)
				(max_width 2)
				(curved_edges yes)
				(filter_ratio 0.9)
				(enabled no)
				(allow_two_segments yes)
				(prefer_zone_connections yes)
			)
		)
		(pad "10" smd roundrect
			(at 0.248 1.937)
			(size 0.25 0.825)
			(layers "F.Cu" "F.Mask" "F.Paste")
			(roundrect_rratio 0.25)
			(net 792 "unconnected-(U41-IO1_0-Pad10)")
			(pinfunction "IO1_0")
			(pintype "bidirectional+no_connect")
			(teardrops
				(best_length_ratio 0.2)
				(max_length 1)
				(best_width_ratio 0.9)
				(max_width 2)
				(curved_edges yes)
				(filter_ratio 0.9)
				(enabled yes)
				(allow_two_segments yes)
				(prefer_zone_connections yes)
			)
		)
		(pad "11" smd roundrect
			(at 0.748 1.937)
			(size 0.25 0.825)
			(layers "F.Cu" "F.Mask" "F.Paste")
			(roundrect_rratio 0.25)
			(net 793 "unconnected-(U41-IO1_1-Pad11)")
			(pinfunction "IO1_1")
			(pintype "bidirectional+no_connect")
			(teardrops
				(best_length_ratio 0.2)
				(max_length 1)
				(best_width_ratio 0.9)
				(max_width 2)
				(curved_edges yes)
				(filter_ratio 0.9)
				(enabled yes)
				(allow_two_segments yes)
				(prefer_zone_connections yes)
			)
		)
		(pad "12" smd roundrect
			(at 1.249 1.937)
			(size 0.25 0.825)
			(layers "F.Cu" "F.Mask" "F.Paste")
			(roundrect_rratio 0.25)
			(net 794 "unconnected-(U41-IO1_2-Pad12)")
			(pinfunction "IO1_2")
			(pintype "bidirectional+no_connect")
			(teardrops
				(best_length_ratio 0.2)
				(max_length 1)
				(best_width_ratio 0.9)
				(max_width 2)
				(curved_edges yes)
				(filter_ratio 0.9)
				(enabled yes)
				(allow_two_segments yes)
				(prefer_zone_connections yes)
			)
		)
		(pad "13" smd roundrect
			(at 1.937 1.249)
			(size 0.825 0.25)
			(layers "F.Cu" "F.Mask" "F.Paste")
			(roundrect_rratio 0.25)
			(net 795 "unconnected-(U41-IO1_3-Pad13)")
			(pinfunction "IO1_3")
			(pintype "bidirectional+no_connect")
			(teardrops
				(best_length_ratio 0.2)
				(max_length 1)
				(best_width_ratio 0.9)
				(max_width 2)
				(curved_edges yes)
				(filter_ratio 0.9)
				(enabled yes)
				(allow_two_segments yes)
				(prefer_zone_connections yes)
			)
		)
		(pad "14" smd roundrect
			(at 1.937 0.748)
			(size 0.825 0.25)
			(layers "F.Cu" "F.Mask" "F.Paste")
			(roundrect_rratio 0.25)
			(net 796 "unconnected-(U41-IO1_4-Pad14)")
			(pinfunction "IO1_4")
			(pintype "bidirectional+no_connect")
			(teardrops
				(best_length_ratio 0.2)
				(max_length 1)
				(best_width_ratio 0.9)
				(max_width 2)
				(curved_edges yes)
				(filter_ratio 0.9)
				(enabled yes)
				(allow_two_segments yes)
				(prefer_zone_connections yes)
			)
		)
		(pad "15" smd roundrect
			(at 1.937 0.248)
			(size 0.825 0.25)
			(layers "F.Cu" "F.Mask" "F.Paste")
			(roundrect_rratio 0.25)
			(net 797 "unconnected-(U41-IO1_5-Pad15)")
			(pinfunction "IO1_5")
			(pintype "bidirectional+no_connect")
			(teardrops
				(best_length_ratio 0.2)
				(max_length 1)
				(best_width_ratio 0.9)
				(max_width 2)
				(curved_edges yes)
				(filter_ratio 0.9)
				(enabled yes)
				(allow_two_segments yes)
				(prefer_zone_connections yes)
			)
		)
		(pad "16" smd roundrect
			(at 1.937 -0.25)
			(size 0.825 0.25)
			(layers "F.Cu" "F.Mask" "F.Paste")
			(roundrect_rratio 0.25)
			(net 798 "unconnected-(U41-IO1_6-Pad16)")
			(pinfunction "IO1_6")
			(pintype "bidirectional+no_connect")
			(teardrops
				(best_length_ratio 0.2)
				(max_length 1)
				(best_width_ratio 0.9)
				(max_width 2)
				(curved_edges yes)
				(filter_ratio 0.9)
				(enabled yes)
				(allow_two_segments yes)
				(prefer_zone_connections yes)
			)
		)
		(pad "17" smd roundrect
			(at 1.937 -0.75)
			(size 0.825 0.25)
			(layers "F.Cu" "F.Mask" "F.Paste")
			(roundrect_rratio 0.25)
			(net 799 "unconnected-(U41-IO1_7-Pad17)")
			(pinfunction "IO1_7")
			(pintype "bidirectional+no_connect")
			(teardrops
				(best_length_ratio 0.2)
				(max_length 1)
				(best_width_ratio 0.9)
				(max_width 2)
				(curved_edges yes)
				(filter_ratio 0.9)
				(enabled yes)
				(allow_two_segments yes)
				(prefer_zone_connections yes)
			)
		)
		(pad "18" smd roundrect
			(at 1.937 -1.25)
			(size 0.825 0.25)
			(layers "F.Cu" "F.Mask" "F.Paste")
			(roundrect_rratio 0.25)
			(net 633 "Net-(U41-A0)")
			(pinfunction "A0")
			(pintype "input")
			(teardrops
				(best_length_ratio 0.2)
				(max_length 1)
				(best_width_ratio 0.9)
				(max_width 2)
				(curved_edges yes)
				(filter_ratio 0.9)
				(enabled yes)
				(allow_two_segments yes)
				(prefer_zone_connections yes)
			)
		)
		(pad "19" smd roundrect
			(at 1.249 -1.938)
			(size 0.25 0.825)
			(layers "F.Cu" "F.Mask" "F.Paste")
			(roundrect_rratio 0.25)
			(net 635 "Net-(U41-SCL)")
			(pinfunction "SCL")
			(pintype "input")
			(teardrops
				(best_length_ratio 0.2)
				(max_length 1)
				(best_width_ratio 0.9)
				(max_width 2)
				(curved_edges yes)
				(filter_ratio 0.9)
				(enabled yes)
				(allow_two_segments yes)
				(prefer_zone_connections yes)
			)
		)
		(pad "20" smd roundrect
			(at 0.748 -1.938)
			(size 0.25 0.825)
			(layers "F.Cu" "F.Mask" "F.Paste")
			(roundrect_rratio 0.25)
			(net 634 "Net-(U41-SDA)")
			(pinfunction "SDA")
			(pintype "bidirectional")
			(teardrops
				(best_length_ratio 0.2)
				(max_length 1)
				(best_width_ratio 0.9)
				(max_width 2)
				(curved_edges yes)
				(filter_ratio 0.9)
				(enabled yes)
				(allow_two_segments yes)
				(prefer_zone_connections yes)
			)
		)
		(pad "21" smd roundrect
			(at 0.248 -1.938)
			(size 0.25 0.825)
			(layers "F.Cu" "F.Mask" "F.Paste")
			(roundrect_rratio 0.25)
			(net 2 "+3V3")
			(pinfunction "VDD")
			(pintype "power_in")
			(teardrops
				(best_length_ratio 0.2)
				(max_length 1)
				(best_width_ratio 0.9)
				(max_width 2)
				(curved_edges yes)
				(filter_ratio 0.9)
				(enabled yes)
				(allow_two_segments yes)
				(prefer_zone_connections yes)
			)
		)
		(pad "22" smd roundrect
			(at -0.25 -1.938)
			(size 0.25 0.825)
			(layers "F.Cu" "F.Mask" "F.Paste")
			(roundrect_rratio 0.25)
			(net 636 "Net-(U41-~{INT})")
			(pinfunction "~{INT}")
			(pintype "output")
			(teardrops
				(best_length_ratio 0.2)
				(max_length 1)
				(best_width_ratio 0.9)
				(max_width 2)
				(curved_edges yes)
				(filter_ratio 0.9)
				(enabled yes)
				(allow_two_segments yes)
				(prefer_zone_connections yes)
			)
		)
		(pad "23" smd roundrect
			(at -0.75 -1.938)
			(size 0.25 0.825)
			(layers "F.Cu" "F.Mask" "F.Paste")
			(roundrect_rratio 0.25)
			(net 638 "Net-(U41-A1)")
			(pinfunction "A1")
			(pintype "input")
			(teardrops
				(best_length_ratio 0.2)
				(max_length 1)
				(best_width_ratio 0.9)
				(max_width 2)
				(curved_edges yes)
				(filter_ratio 0.9)
				(enabled yes)
				(allow_two_segments yes)
				(prefer_zone_connections yes)
			)
		)
		(pad "24" smd roundrect
			(at -1.25 -1.938)
			(size 0.25 0.825)
			(layers "F.Cu" "F.Mask" "F.Paste")
			(roundrect_rratio 0.25)
			(net 637 "Net-(U41-~{RESET})")
			(pinfunction "~{RESET}")
			(pintype "input")
			(teardrops
				(best_length_ratio 0.2)
				(max_length 1)
				(best_width_ratio 0.9)
				(max_width 2)
				(curved_edges yes)
				(filter_ratio 0.9)
				(enabled yes)
				(allow_two_segments yes)
				(prefer_zone_connections yes)
			)
		)
		(pad "25" smd rect
			(at 0 0)
			(size 2.1 2.1)
			(layers "F.Cu" "F.Mask")
			(net 1 "GND")
			(pinfunction "GND")
			(pintype "passive")
			(teardrops
				(best_length_ratio 0.2)
				(max_length 1)
				(best_width_ratio 0.9)
				(max_width 2)
				(curved_edges yes)
				(filter_ratio 0.9)
				(enabled no)
				(allow_two_segments yes)
				(prefer_zone_connections yes)
			)
		)
	)
)
